# BASEBOARD_FAB2 (Tioga Pass) — schematic netlist excerpt (pin names and nets, part order shuffled) for the footprints in the layout excerpt that follows; sources: Cadence DE-HDL packaged netlist, KiCad conversion of Wiwynn_Tioga_Pass_MB.brd

U7F1  W25Q256  IC  pkg XSOI  page 153
  HOLD_N_IO(3)  = PU_BIOS_SPI_HOLD0_N
  VCC  = P3V3_STBY
  RESET_N  = PU_SPI0_RST
  NC(6)  = TP_SPI_0_6
  NC(5)  = TP_SPI_0_5
  NC(4)  = TP_SPI_0_4
  CS_N  = SPI_CS0_PRIMARY_R_N
  DO_IO(1)  = SPI_MISO_R0
  WP_N_IO(2)  = PU_BIOS_SPI_WP0_N
  GND  = GND
  NC(3)  = TP_SPI_0_3
  NC(2)  = TP_SPI_0_2
  NC(1)  = TP_SPI_0_1
  NC(0)  = TP_SPI_0_0
  DI_IO(0)  = SPI_SWITCH_MOSI_R0
  CLK  = SPI_CLK_R0

(kicad_pcb
	(version 20260206)
	(generator "pcbnew")
	(generator_version "10.0")
	(general
		(thickness 1.6)
		(legacy_teardrops no)
	)
	(paper "A4")
	(title_block
		(title "Wiwynn_Tioga_Pass_MB.brd")
		(comment 1 "Tioga Pass / footprints 1126-1126 of 4770")
	)
	(layers
		(0 "F.Cu" signal "TOP")
		(4 "In1.Cu" signal "L2GND")
		(6 "In2.Cu" signal "L3")
		(8 "In3.Cu" signal "L4GND")
		(10 "In4.Cu" signal "L5")
		(12 "In5.Cu" signal "L6GND")
		(14 "In6.Cu" signal "L7VCC")
		(16 "In7.Cu" signal "L8VCC")
		(18 "In8.Cu" signal "L9GND")
		(20 "In9.Cu" signal "L10")
		(22 "In10.Cu" signal "L11GND")
		(24 "In11.Cu" signal "L12")
		(26 "In12.Cu" signal "L13GND")
		(2 "B.Cu" signal "BOTTOM")
		(9 "F.Adhes" user "F.Adhesive")
		(11 "B.Adhes" user "B.Adhesive")
		(13 "F.Paste" user "Package Geometry/Pastemask Top")
		(15 "B.Paste" user "Package Geometry/Pastemask Bottom")
		(5 "F.SilkS" user "Ref Des/Silkscreen Top")
		(7 "B.SilkS" user "Ref Des/Silkscreen Bottom")
		(1 "F.Mask" user "Board Geometry/Soldermask Top")
		(3 "B.Mask" user "Board Geometry/Soldermask Bottom")
		(17 "Dwgs.User" user "User.Drawings")
		(19 "Cmts.User" user "User.Comments")
		(21 "Eco1.User" user "User.Eco1")
		(23 "Eco2.User" user "User.Eco2")
		(25 "Edge.Cuts" user "Board Geometry/Outline")
		(27 "Margin" user)
		(31 "F.CrtYd" user "Package Geometry/Place Bound Top")
		(29 "B.CrtYd" user "Package Geometry/Place Bound Bottom")
		(35 "F.Fab" user "Ref Des/Assembly Top")
		(33 "B.Fab" user "Ref Des/Assembly Bottom")
	)
	(footprint ""
		(layer "F.Cu")
		(at 398.093946 -47.22368 180)
		(property "Reference" "U7F1"
			(at 8.94334 -3.18643 0)
			(unlocked yes)
			(layer "F.SilkS")
			(effects
				(font
					(size 0.7874 0.5842)
					(thickness 0.1524)
				)
				(justify left)
			)
		)
		(property "Value" ""
			(at 0 0 180)
			(layer "F.Fab")
			(effects
				(font
					(size 1.27 1.27)
				)
			)
		)
		(duplicate_pad_numbers_are_jumpers no)
		(fp_line
			(start 11.645392 10.819892)
			(end -2.094738 10.819892)
			(stroke
				(width 0.1524)
				(type default)
			)
			(layer "F.SilkS")
		)
		(fp_line
			(start 11.645392 -1.929892)
			(end 11.645392 10.819892)
			(stroke
				(width 0.1524)
				(type default)
			)
			(layer "F.SilkS")
		)
		(fp_line
			(start -2.094738 10.819892)
			(end -2.094738 -1.929892)
			(stroke
				(width 0.1524)
				(type default)
			)
			(layer "F.SilkS")
		)
		(fp_line
			(start -2.094738 -1.929892)
			(end 11.645392 -1.929892)
			(stroke
				(width 0.1524)
				(type default)
			)
			(layer "F.SilkS")
		)
		(fp_circle
			(center -1.604264 -2.699512)
			(end -1.731264 -2.699512)
			(stroke
				(width 0.762)
				(type default)
			)
			(fill no)
			(layer "F.SilkS")
		)
		(fp_rect
			(start 11.645392 12.260326)
			(end 15.404846 -3.284474)
			(stroke
				(width 0)
				(type default)
			)
			(fill no)
			(layer "F.CrtYd")
		)
		(fp_rect
			(start -5.600954 12.260326)
			(end -2.094738 -3.284474)
			(stroke
				(width 0)
				(type default)
			)
			(fill no)
			(layer "F.CrtYd")
		)
		(fp_poly
			(pts
				(xy 7.569962 10.819892) (xy 6.970014 12.21994) (xy 2.629916 12.21994) (xy 2.029968 10.819892)
			)
			(stroke
				(width 0)
				(type default)
			)
			(fill no)
			(layer "F.CrtYd")
		)
		(fp_poly
			(pts
				(xy 2.029968 -1.929892) (xy 2.629916 -3.32994) (xy 6.970014 -3.32994) (xy 7.569962 -1.929892)
			)
			(stroke
				(width 0)
				(type default)
			)
			(fill no)
			(layer "F.CrtYd")
		)
		(fp_poly
			(pts
				(xy -2.094738 10.819892) (xy 11.645392 10.819892) (xy 11.645392 -1.929892) (xy -2.094738 -1.929892)
			)
			(stroke
				(width 0)
				(type default)
			)
			(fill no)
			(layer "F.CrtYd")
		)
		(fp_line
			(start 11.645392 10.819892)
			(end -2.094738 10.819892)
			(stroke
				(width 0.1)
				(type default)
			)
			(layer "F.Fab")
		)
		(fp_line
			(start 11.645392 -1.929892)
			(end 11.645392 10.819892)
			(stroke
				(width 0.1)
				(type default)
			)
			(layer "F.Fab")
		)
		(fp_line
			(start 7.569962 10.819892)
			(end 6.970014 12.21994)
			(stroke
				(width 0.1)
				(type default)
			)
			(layer "F.Fab")
		)
		(fp_line
			(start 6.970014 12.21994)
			(end 2.629916 12.21994)
			(stroke
				(width 0.1)
				(type default)
			)
			(layer "F.Fab")
		)
		(fp_line
			(start 6.970014 -3.32994)
			(end 7.569962 -1.929892)
			(stroke
				(width 0.1)
				(type default)
			)
			(layer "F.Fab")
		)
		(fp_line
			(start 2.629916 12.21994)
			(end 2.029968 10.819892)
			(stroke
				(width 0.1)
				(type default)
			)
			(layer "F.Fab")
		)
		(fp_line
			(start 2.629916 -3.32994)
			(end 6.970014 -3.32994)
			(stroke
				(width 0.1)
				(type default)
			)
			(layer "F.Fab")
		)
		(fp_line
			(start 2.029968 -1.929892)
			(end 2.629916 -3.32994)
			(stroke
				(width 0.1)
				(type default)
			)
			(layer "F.Fab")
		)
		(fp_line
			(start -2.094738 10.819892)
			(end -2.094738 -1.929892)
			(stroke
				(width 0.1)
				(type default)
			)
			(layer "F.Fab")
		)
		(fp_line
			(start -2.094738 -1.929892)
			(end 11.645392 -1.929892)
			(stroke
				(width 0.1)
				(type default)
			)
			(layer "F.Fab")
		)
		(fp_circle
			(center -2.645918 -0.940054)
			(end -2.772918 -0.940054)
			(stroke
				(width 0.254)
				(type default)
			)
			(fill no)
			(layer "F.Fab")
		)
		(fp_text user "9"
			(at 12.861798 10.70102 270)
			(unlocked yes)
			(layer "F.SilkS")
			(effects
				(font
					(size 0.7874 0.5842)
					(thickness 0.1524)
				)
				(justify left)
			)
		)
		(fp_text user "16"
			(at 11.13917 -2.15392 270)
			(unlocked yes)
			(layer "F.SilkS")
			(effects
				(font
					(size 0.7874 0.5842)
					(thickness 0.1524)
				)
				(justify left)
			)
		)
		(fp_text user "8"
			(at -1.215136 11.422634 0)
			(unlocked yes)
			(layer "F.SilkS")
			(effects
				(font
					(size 0.7874 0.5842)
					(thickness 0.1524)
				)
				(justify left)
			)
		)
		(fp_text user "9"
			(at 11.862054 9.20369 180)
			(unlocked yes)
			(layer "F.Fab")
			(effects
				(font
					(size 0.254 0.254)
					(thickness 0.000001)
				)
				(justify left)
			)
		)
		(fp_text user "16"
			(at 11.646916 0.367792 180)
			(unlocked yes)
			(layer "F.Fab")
			(effects
				(font
					(size 0.254 0.254)
					(thickness 0.000001)
				)
				(justify left)
			)
		)
		(fp_text user "8"
			(at -2.3241 8.86333 180)
			(unlocked yes)
			(layer "F.Fab")
			(effects
				(font
					(size 0.635 0.635)
					(thickness 0.1524)
				)
				(justify left)
			)
		)
		(pad "1" smd rect
			(at 0 0 180)
			(size 1.9304 0.635)
			(layers "F.Cu" "F.Mask" "F.Paste")
			(net "PU_BIOS_SPI_HOLD0_N")
		)
		(pad "2" smd rect
			(at 0 1.27 180)
			(size 1.9304 0.635)
			(layers "F.Cu" "F.Mask" "F.Paste")
			(net "P3V3_STBY")
		)
		(pad "3" smd rect
			(at 0 2.54 180)
			(size 1.9304 0.635)
			(layers "F.Cu" "F.Mask" "F.Paste")
			(net "PU_SPI0_RST")
		)
		(pad "4" smd rect
			(at 0 3.81 180)
			(size 1.9304 0.635)
			(layers "F.Cu" "F.Mask" "F.Paste")
			(net "TP_SPI_0_6")
		)
		(pad "5" smd rect
			(at 0 5.08 180)
			(size 1.9304 0.635)
			(layers "F.Cu" "F.Mask" "F.Paste")
			(net "TP_SPI_0_5")
		)
		(pad "6" smd rect
			(at 0 6.35 180)
			(size 1.9304 0.635)
			(layers "F.Cu" "F.Mask" "F.Paste")
			(net "TP_SPI_0_4")
		)
		(pad "7" smd rect
			(at 0 7.62 180)
			(size 1.9304 0.635)
			(layers "F.Cu" "F.Mask" "F.Paste")
			(net "SPI_CS0_PRIMARY_R_N")
		)
		(pad "8" smd rect
			(at 0 8.89 180)
			(size 1.9304 0.635)
			(layers "F.Cu" "F.Mask" "F.Paste")
			(net "SPI_MISO_R0")
		)
		(pad "9" smd rect
			(at 9.5504 8.89 180)
			(size 1.9304 0.635)
			(layers "F.Cu" "F.Mask" "F.Paste")
			(net "PU_BIOS_SPI_WP0_N")
		)
		(pad "10" smd rect
			(at 9.5504 7.62 180)
			(size 1.9304 0.635)
			(layers "F.Cu" "F.Mask" "F.Paste")
			(net "GND")
		)
		(pad "11" smd rect
			(at 9.5504 6.35 180)
			(size 1.9304 0.635)
			(layers "F.Cu" "F.Mask" "F.Paste")
			(net "TP_SPI_0_3")
		)
		(pad "12" smd rect
			(at 9.5504 5.08 180)
			(size 1.9304 0.635)
			(layers "F.Cu" "F.Mask" "F.Paste")
			(net "TP_SPI_0_2")
		)
		(pad "13" smd rect
			(at 9.5504 3.81 180)
			(size 1.9304 0.635)
			(layers "F.Cu" "F.Mask" "F.Paste")
			(net "TP_SPI_0_1")
		)
		(pad "14" smd rect
			(at 9.5504 2.54 180)
			(size 1.9304 0.635)
			(layers "F.Cu" "F.Mask" "F.Paste")
			(net "TP_SPI_0_0")
		)
		(pad "15" smd rect
			(at 9.5504 1.27 180)
			(size 1.9304 0.635)
			(layers "F.Cu" "F.Mask" "F.Paste")
			(net "SPI_SWITCH_MOSI_R0")
		)
		(pad "16" smd rect
			(at 9.5504 0 180)
			(size 1.9304 0.635)
			(layers "F.Cu" "F.Mask" "F.Paste")
			(net "SPI_CLK_R0")
		)
	)
)
